(kicad_pcb
	(version 20260206)
	(generator "pcbnew")
	(generator_version "10.0")
	(general
		(thickness 1.6)
		(legacy_teardrops no)
	)
	(paper "A4")
	(title_block
		(title "03242023_DA0F0TMBIJ0_F0T_Motherboard_J_brd_V01_OCP.brd")
		(comment 1 "Grand Teton / footprints 4535-4539 of 6105")
	)
	(layers
		(0 "F.Cu" signal "TOP")
		(4 "In1.Cu" signal "GND")
		(6 "In2.Cu" signal "IN1")
		(8 "In3.Cu" signal "GND1")
		(10 "In4.Cu" signal "IN2")
		(12 "In5.Cu" signal "GND2")
		(14 "In6.Cu" signal "IN3")
		(16 "In7.Cu" signal "GND3")
		(18 "In8.Cu" signal "VCC")
		(20 "In9.Cu" signal "VCC1")
		(22 "In10.Cu" signal "GND4")
		(24 "In11.Cu" signal "IN4")
		(26 "In12.Cu" signal "GND5")
		(28 "In13.Cu" signal "IN5")
		(30 "In14.Cu" signal "GND6")
		(32 "In15.Cu" signal "IN6")
		(34 "In16.Cu" signal "GND7")
		(2 "B.Cu" signal "BOTTOM")
		(9 "F.Adhes" user "F.Adhesive")
		(11 "B.Adhes" user "B.Adhesive")
		(13 "F.Paste" user "Package Geometry/Pastemask Top")
		(15 "B.Paste" user "Package Geometry/Pastemask Bottom")
		(5 "F.SilkS" user "Ref Des/Silkscreen Top")
		(7 "B.SilkS" user "Ref Des/Silkscreen Bottom")
		(1 "F.Mask" user "Board Geometry/Soldermask Top")
		(3 "B.Mask" user "Board Geometry/Soldermask Bottom")
		(17 "Dwgs.User" user "User.Drawings")
		(19 "Cmts.User" user "User.Comments")
		(21 "Eco1.User" user "User.Eco1")
		(23 "Eco2.User" user "User.Eco2")
		(25 "Edge.Cuts" user "Board Geometry/Outline")
		(27 "Margin" user)
		(31 "F.CrtYd" user "Package Geometry/Place Bound Top")
		(29 "B.CrtYd" user "Package Geometry/Place Bound Bottom")
		(35 "F.Fab" user "Ref Des/Assembly Top")
		(33 "B.Fab" user "Ref Des/Assembly Bottom")
	)
	(footprint ""
		(layer "B.Cu")
		(at 171.755562 -113.37544 90)
		(property "Reference" "C1895"
			(at 0 0 90)
			(layer "B.SilkS")
			(hide yes)
			(effects
				(font
					(size 1.27 1.27)
				)
				(justify mirror)
			)
		)
		(property "Value" ""
			(at 0 0 90)
			(layer "B.Fab")
			(effects
				(font
					(size 1.27 1.27)
				)
				(justify mirror)
			)
		)
		(duplicate_pad_numbers_are_jumpers no)
		(fp_line
			(start 0.69215 -0.2921)
			(end -0.69215 -0.2921)
			(stroke
				(width 0.1524)
				(type default)
			)
			(layer "B.SilkS")
		)
		(fp_line
			(start -0.69215 -0.2921)
			(end -0.69215 0.2921)
			(stroke
				(width 0.1524)
				(type default)
			)
			(layer "B.SilkS")
		)
		(fp_line
			(start 0.69215 0.2921)
			(end 0.69215 -0.2921)
			(stroke
				(width 0.1524)
				(type default)
			)
			(layer "B.SilkS")
		)
		(fp_line
			(start -0.69215 0.2921)
			(end 0.69215 0.2921)
			(stroke
				(width 0.1524)
				(type default)
			)
			(layer "B.SilkS")
		)
		(fp_line
			(start 0.51435 -0.2794)
			(end -0.51435 -0.2794)
			(stroke
				(width 0.1)
				(type default)
			)
			(layer "B.Fab")
		)
		(fp_line
			(start -0.51435 -0.2794)
			(end -0.51435 0.2794)
			(stroke
				(width 0.1)
				(type default)
			)
			(layer "B.Fab")
		)
		(fp_line
			(start 0.51435 0.2794)
			(end 0.51435 -0.2794)
			(stroke
				(width 0.1)
				(type default)
			)
			(layer "B.Fab")
		)
		(fp_line
			(start -0.51435 0.2794)
			(end 0.51435 0.2794)
			(stroke
				(width 0.1)
				(type default)
			)
			(layer "B.Fab")
		)
		(pad "1" smd circle
			(at 0.40005 0 270)
			(size 0 0)
			(layers "B.Cu" "B.Mask" "B.Paste")
			(net "P3V3_AUX_FPGA_VCCIO0")
		)
		(pad "2" smd circle
			(at -0.40005 0 270)
			(size 0 0)
			(layers "B.Cu" "B.Mask" "B.Paste")
			(net "GND")
		)
		(zone
			(layer "B.Cu")
			(hatch none 0.5)
			(connect_pads
				(clearance 0)
			)
			(min_thickness 0.25)
			(keepout
				(tracks not_allowed)
				(vias allowed)
				(pads allowed)
				(copperpour not_allowed)
				(footprints allowed)
			)
			(placement
				(enabled no)
				(sheetname "")
			)
			(fill
				(thermal_gap 0.5)
				(thermal_bridge_width 0.5)
				(island_removal_mode 0)
			)
			(polygon
				(pts
					(xy 171.843192 -113.56594) (xy 171.901358 -113.4745) (xy 171.901358 -113.27511) (xy 171.843192 -113.18494)
					(xy 171.667932 -113.18494) (xy 171.609512 -113.27511) (xy 171.609512 -113.4745) (xy 171.667678 -113.56594)
				)
			)
		)
	)
	(footprint ""
		(layer "B.Cu")
		(at 178.61788 -329.479148)
		(property "Reference" "R1934"
			(at 0 0 0)
			(layer "B.SilkS")
			(hide yes)
			(effects
				(font
					(size 1.27 1.27)
				)
				(justify mirror)
			)
		)
		(property "Value" ""
			(at 0 0 0)
			(layer "B.Fab")
			(effects
				(font
					(size 1.27 1.27)
				)
				(justify mirror)
			)
		)
		(duplicate_pad_numbers_are_jumpers no)
		(fp_line
			(start -0.7874 -0.4064)
			(end -0.7874 0.4064)
			(stroke
				(width 0.1524)
				(type default)
			)
			(layer "B.SilkS")
		)
		(fp_line
			(start -0.7874 0.4064)
			(end 0.7874 0.4064)
			(stroke
				(width 0.1524)
				(type default)
			)
			(layer "B.SilkS")
		)
		(fp_line
			(start 0.7874 -0.4064)
			(end -0.7874 -0.4064)
			(stroke
				(width 0.1524)
				(type default)
			)
			(layer "B.SilkS")
		)
		(fp_line
			(start 0.7874 0.4064)
			(end 0.7874 -0.4064)
			(stroke
				(width 0.1524)
				(type default)
			)
			(layer "B.SilkS")
		)
		(fp_line
			(start -0.67945 -0.3048)
			(end -0.67945 0.3048)
			(stroke
				(width 0.1)
				(type default)
			)
			(layer "B.Fab")
		)
		(fp_line
			(start -0.67945 0.3048)
			(end -0.120396 0.3048)
			(stroke
				(width 0.1)
				(type default)
			)
			(layer "B.Fab")
		)
		(fp_line
			(start -0.12065 -0.3048)
			(end -0.67945 -0.3048)
			(stroke
				(width 0.1)
				(type default)
			)
			(layer "B.Fab")
		)
		(fp_line
			(start -0.12065 -0.2794)
			(end -0.12065 -0.3048)
			(stroke
				(width 0.1)
				(type default)
			)
			(layer "B.Fab")
		)
		(fp_line
			(start -0.120396 0.2794)
			(end 0.12065 0.2794)
			(stroke
				(width 0.1)
				(type default)
			)
			(layer "B.Fab")
		)
		(fp_line
			(start -0.120396 0.3048)
			(end -0.120396 0.2794)
			(stroke
				(width 0.1)
				(type default)
			)
			(layer "B.Fab")
		)
		(fp_line
			(start 0.12065 -0.305054)
			(end 0.12065 -0.2794)
			(stroke
				(width 0.1)
				(type default)
			)
			(layer "B.Fab")
		)
		(fp_line
			(start 0.12065 -0.2794)
			(end -0.12065 -0.2794)
			(stroke
				(width 0.1)
				(type default)
			)
			(layer "B.Fab")
		)
		(fp_line
			(start 0.12065 0.2794)
			(end 0.12065 0.3048)
			(stroke
				(width 0.1)
				(type default)
			)
			(layer "B.Fab")
		)
		(fp_line
			(start 0.12065 0.3048)
			(end 0.67945 0.3048)
			(stroke
				(width 0.1)
				(type default)
			)
			(layer "B.Fab")
		)
		(fp_line
			(start 0.67945 -0.305054)
			(end 0.12065 -0.305054)
			(stroke
				(width 0.1)
				(type default)
			)
			(layer "B.Fab")
		)
		(fp_line
			(start 0.67945 0.3048)
			(end 0.67945 -0.305054)
			(stroke
				(width 0.1)
				(type default)
			)
			(layer "B.Fab")
		)
		(pad "1" smd circle
			(at 0.40005 0 180)
			(size 0 0)
			(layers "B.Cu" "B.Mask" "B.Paste")
			(net "SMB_S3M_CPU1_PIROM_3V3AUX_SCL")
		)
		(pad "2" smd circle
			(at -0.40005 0 180)
			(size 0 0)
			(layers "B.Cu" "B.Mask" "B.Paste")
			(net "SMB_S3M_CPU1_PIROM_3V3AUX_SCL_1")
		)
	)
	(footprint ""
		(layer "B.Cu")
		(at 182.14594 5.461 180)
		(property "Reference" "J80"
			(at 4.24561 -1.143 270)
			(unlocked yes)
			(layer "B.SilkS")
			(effects
				(font
					(size 0.7874 0.5842)
					(thickness 0.1524)
				)
				(justify left mirror)
			)
		)
		(property "Value" ""
			(at 0 0 0)
			(layer "B.Fab")
			(effects
				(font
					(size 1.27 1.27)
				)
				(justify mirror)
			)
		)
		(duplicate_pad_numbers_are_jumpers no)
		(fp_line
			(start 1.2192 2.1082)
			(end 1.2192 -2.1082)
			(stroke
				(width 0.1524)
				(type default)
			)
			(layer "B.SilkS")
		)
		(fp_line
			(start 1.2192 -2.1082)
			(end -1.2192 -2.1082)
			(stroke
				(width 0.1524)
				(type default)
			)
			(layer "B.SilkS")
		)
		(fp_line
			(start -1.2192 2.1082)
			(end 1.2192 2.1082)
			(stroke
				(width 0.1524)
				(type default)
			)
			(layer "B.SilkS")
		)
		(fp_line
			(start -1.2192 -2.1082)
			(end -1.2192 2.1082)
			(stroke
				(width 0.1524)
				(type default)
			)
			(layer "B.SilkS")
		)
		(pad "" np_thru_hole circle
			(at -3.4671 -1.27 90)
			(size 1.0414 1.0414)
			(drill 1.0414)
			(layers "*.Cu" "*.Mask")
			(clearance 0.381)
			(thermal_gap 0.381)
		)
		(pad "" np_thru_hole circle
			(at -3.4671 1.27 90)
			(size 1.0414 1.0414)
			(drill 1.0414)
			(layers "*.Cu" "*.Mask")
			(clearance 0.381)
			(thermal_gap 0.381)
		)
		(pad "" np_thru_hole circle
			(at 2.8829 -1.27 90)
			(size 1.0414 1.0414)
			(drill 1.0414)
			(layers "*.Cu" "*.Mask")
			(clearance 0.381)
			(thermal_gap 0.381)
		)
		(pad "" np_thru_hole circle
			(at 2.8829 1.27 90)
			(size 1.0414 1.0414)
			(drill 1.0414)
			(layers "*.Cu" "*.Mask")
			(clearance 0.381)
			(thermal_gap 0.381)
		)
		(pad "1" smd rect
			(at -0.8255 -0.249936 90)
			(size 0.3048 0.508)
			(layers "B.Cu" "B.Mask" "B.Paste")
			(net "DELTA_L_85_10INCH_IN4_DP")
		)
		(pad "2" smd rect
			(at -0.8255 0.249936 90)
			(size 0.3048 0.508)
			(layers "B.Cu" "B.Mask" "B.Paste")
			(net "DELTA_L_85_10INCH_IN4_DN")
		)
		(pad "3" smd circle
			(at 0 0)
			(size 0 0)
			(layers "B.Cu" "B.Mask" "B.Paste")
			(net "DELTA_L_GND_1")
		)
		(zone
			(layers "F.Cu" "B.Cu" "In1.Cu" "In2.Cu" "In3.Cu" "In4.Cu" "In5.Cu" "In6.Cu"
				"In7.Cu" "In8.Cu" "In9.Cu" "In10.Cu" "In11.Cu" "In12.Cu" "In13.Cu" "In14.Cu"
				"In15.Cu" "In16.Cu"
			)
			(hatch none 0.5)
			(connect_pads
				(clearance 0)
			)
			(min_thickness 0.25)
			(keepout
				(tracks not_allowed)
				(vias allowed)
				(pads allowed)
				(copperpour not_allowed)
				(footprints allowed)
			)
			(placement
				(enabled no)
				(sheetname "")
			)
			(fill
				(thermal_gap 0.5)
				(thermal_bridge_width 0.5)
				(island_removal_mode 0)
			)
			(polygon
				(pts
					(arc
						(start 180.19014 4.191)
						(mid 178.33594 4.191)
						(end 180.19014 4.191)
					)
				)
			)
		)
		(zone
			(layers "F.Cu" "B.Cu" "In1.Cu" "In2.Cu" "In3.Cu" "In4.Cu" "In5.Cu" "In6.Cu"
				"In7.Cu" "In8.Cu" "In9.Cu" "In10.Cu" "In11.Cu" "In12.Cu" "In13.Cu" "In14.Cu"
				"In15.Cu" "In16.Cu"
			)
			(hatch none 0.5)
			(connect_pads
				(clearance 0)
			)
			(min_thickness 0.25)
			(keepout
				(tracks not_allowed)
				(vias allowed)
				(pads allowed)
				(copperpour not_allowed)
				(footprints allowed)
			)
			(placement
				(enabled no)
				(sheetname "")
			)
			(fill
				(thermal_gap 0.5)
				(thermal_bridge_width 0.5)
				(island_removal_mode 0)
			)
			(polygon
				(pts
					(arc
						(start 180.19014 6.731)
						(mid 178.33594 6.731)
						(end 180.19014 6.731)
					)
				)
			)
		)
		(zone
			(layers "F.Cu" "B.Cu" "In1.Cu" "In2.Cu" "In3.Cu" "In4.Cu" "In5.Cu" "In6.Cu"
				"In7.Cu" "In8.Cu" "In9.Cu" "In10.Cu" "In11.Cu" "In12.Cu" "In13.Cu" "In14.Cu"
				"In15.Cu" "In16.Cu"
			)
			(hatch none 0.5)
			(connect_pads
				(clearance 0)
			)
			(min_thickness 0.25)
			(keepout
				(tracks not_allowed)
				(vias allowed)
				(pads allowed)
				(copperpour not_allowed)
				(footprints allowed)
			)
			(placement
				(enabled no)
				(sheetname "")
			)
			(fill
				(thermal_gap 0.5)
				(thermal_bridge_width 0.5)
				(island_removal_mode 0)
			)
			(polygon
				(pts
					(arc
						(start 186.54014 4.191)
						(mid 184.68594 4.191)
						(end 186.54014 4.191)
					)
				)
			)
		)
		(zone
			(layers "F.Cu" "B.Cu" "In1.Cu" "In2.Cu" "In3.Cu" "In4.Cu" "In5.Cu" "In6.Cu"
				"In7.Cu" "In8.Cu" "In9.Cu" "In10.Cu" "In11.Cu" "In12.Cu" "In13.Cu" "In14.Cu"
				"In15.Cu" "In16.Cu"
			)
			(hatch none 0.5)
			(connect_pads
				(clearance 0)
			)
			(min_thickness 0.25)
			(keepout
				(tracks not_allowed)
				(vias allowed)
				(pads allowed)
				(copperpour not_allowed)
				(footprints allowed)
			)
			(placement
				(enabled no)
				(sheetname "")
			)
			(fill
				(thermal_gap 0.5)
				(thermal_bridge_width 0.5)
				(island_removal_mode 0)
			)
			(polygon
				(pts
					(arc
						(start 186.54014 6.731)
						(mid 184.68594 6.731)
						(end 186.54014 6.731)
					)
				)
			)
		)
		(zone
			(layer "B.Cu")
			(hatch none 0.5)
			(connect_pads
				(clearance 0)
			)
			(min_thickness 0.25)
			(keepout
				(tracks not_allowed)
				(vias allowed)
				(pads allowed)
				(copperpour not_allowed)
				(footprints allowed)
			)
			(placement
				(enabled no)
				(sheetname "")
			)
			(fill
				(thermal_gap 0.5)
				(thermal_bridge_width 0.5)
				(island_removal_mode 0)
			)
			(polygon
				(pts
					(xy 183.26354 6.00964) (xy 183.26354 5.914136) (xy 182.66664 5.914136) (xy 182.66664 5.507736)
					(xy 183.26354 5.507736) (xy 183.26354 5.414264) (xy 182.66664 5.414264) (xy 182.66664 5.007864)
					(xy 183.26354 5.007864) (xy 183.26354 4.91236) (xy 182.56504 4.91236) (xy 182.56504 6.00964)
				)
			)
		)
	)
	(footprint ""
		(layer "B.Cu")
		(at 24.887682 -164.086286 180)
		(property "Reference" "PR4252"
			(at 0 0 0)
			(layer "B.SilkS")
			(hide yes)
			(effects
				(font
					(size 1.27 1.27)
				)
				(justify mirror)
			)
		)
		(property "Value" ""
			(at 0 0 0)
			(layer "B.Fab")
			(effects
				(font
					(size 1.27 1.27)
				)
				(justify mirror)
			)
		)
		(duplicate_pad_numbers_are_jumpers no)
		(fp_line
			(start 0.7874 0.4064)
			(end 0.7874 -0.4064)
			(stroke
				(width 0.1524)
				(type default)
			)
			(layer "B.SilkS")
		)
		(fp_line
			(start 0.7874 -0.4064)
			(end -0.7874 -0.4064)
			(stroke
				(width 0.1524)
				(type default)
			)
			(layer "B.SilkS")
		)
		(fp_line
			(start -0.7874 0.4064)
			(end 0.7874 0.4064)
			(stroke
				(width 0.1524)
				(type default)
			)
			(layer "B.SilkS")
		)
		(fp_line
			(start -0.7874 -0.4064)
			(end -0.7874 0.4064)
			(stroke
				(width 0.1524)
				(type default)
			)
			(layer "B.SilkS")
		)
		(fp_line
			(start 0.67945 0.3048)
			(end 0.67945 -0.305054)
			(stroke
				(width 0.1)
				(type default)
			)
			(layer "B.Fab")
		)
		(fp_line
			(start 0.67945 -0.305054)
			(end 0.12065 -0.305054)
			(stroke
				(width 0.1)
				(type default)
			)
			(layer "B.Fab")
		)
		(fp_line
			(start 0.12065 0.3048)
			(end 0.67945 0.3048)
			(stroke
				(width 0.1)
				(type default)
			)
			(layer "B.Fab")
		)
		(fp_line
			(start 0.12065 0.2794)
			(end 0.12065 0.3048)
			(stroke
				(width 0.1)
				(type default)
			)
			(layer "B.Fab")
		)
		(fp_line
			(start 0.12065 -0.2794)
			(end -0.12065 -0.2794)
			(stroke
				(width 0.1)
				(type default)
			)
			(layer "B.Fab")
		)
		(fp_line
			(start 0.12065 -0.305054)
			(end 0.12065 -0.2794)
			(stroke
				(width 0.1)
				(type default)
			)
			(layer "B.Fab")
		)
		(fp_line
			(start -0.120396 0.3048)
			(end -0.120396 0.2794)
			(stroke
				(width 0.1)
				(type default)
			)
			(layer "B.Fab")
		)
		(fp_line
			(start -0.120396 0.2794)
			(end 0.12065 0.2794)
			(stroke
				(width 0.1)
				(type default)
			)
			(layer "B.Fab")
		)
		(fp_line
			(start -0.12065 -0.2794)
			(end -0.12065 -0.3048)
			(stroke
				(width 0.1)
				(type default)
			)
			(layer "B.Fab")
		)
		(fp_line
			(start -0.12065 -0.3048)
			(end -0.67945 -0.3048)
			(stroke
				(width 0.1)
				(type default)
			)
			(layer "B.Fab")
		)
		(fp_line
			(start -0.67945 0.3048)
			(end -0.120396 0.3048)
			(stroke
				(width 0.1)
				(type default)
			)
			(layer "B.Fab")
		)
		(fp_line
			(start -0.67945 -0.3048)
			(end -0.67945 0.3048)
			(stroke
				(width 0.1)
				(type default)
			)
			(layer "B.Fab")
		)
		(pad "1" smd circle
			(at 0.40005 0)
			(size 0 0)
			(layers "B.Cu" "B.Mask" "B.Paste")
			(net "NC_PVCCD_HV_CPU1_ACSP3")
		)
		(pad "2" smd circle
			(at -0.40005 0)
			(size 0 0)
			(layers "B.Cu" "B.Mask" "B.Paste")
			(net "GND")
		)
	)
	(footprint ""
		(layer "B.Cu")
		(at 349.028004 -357.239316 180)
		(property "Reference" "C3270"
			(at 0 0 0)
			(layer "B.SilkS")
			(hide yes)
			(effects
				(font
					(size 1.27 1.27)
				)
				(justify mirror)
			)
		)
		(property "Value" ""
			(at 0 0 0)
			(layer "B.Fab")
			(effects
				(font
					(size 1.27 1.27)
				)
				(justify mirror)
			)
		)
		(duplicate_pad_numbers_are_jumpers no)
		(fp_line
			(start 1.2954 0.5842)
			(end 1.2954 -0.5842)
			(stroke
				(width 0.1524)
				(type default)
			)
			(layer "B.SilkS")
		)
		(fp_line
			(start 1.2954 -0.5842)
			(end -1.2954 -0.5842)
			(stroke
				(width 0.1524)
				(type default)
			)
			(layer "B.SilkS")
		)
		(fp_line
			(start 0 -0.5842)
			(end 0 0.5842)
			(stroke
				(width 0.1524)
				(type default)
			)
			(layer "B.SilkS")
		)
		(fp_line
			(start -1.2954 0.5842)
			(end 1.2954 0.5842)
			(stroke
				(width 0.1524)
				(type default)
			)
			(layer "B.SilkS")
		)
		(fp_line
			(start -1.2954 -0.5842)
			(end -1.2954 0.5842)
			(stroke
				(width 0.1524)
				(type default)
			)
			(layer "B.SilkS")
		)
		(fp_line
			(start 1.1938 0.4064)
			(end 1.1938 -0.4064)
			(stroke
				(width 0.1)
				(type default)
			)
			(layer "B.Fab")
		)
		(fp_line
			(start 1.1938 -0.4064)
			(end 0.8636 -0.4064)
			(stroke
				(width 0.1)
				(type default)
			)
			(layer "B.Fab")
		)
		(fp_line
			(start 0.8636 0.4572)
			(end 0.8636 0.4064)
			(stroke
				(width 0.1)
				(type default)
			)
			(layer "B.Fab")
		)
		(fp_line
			(start 0.8636 0.4064)
			(end 1.1938 0.4064)
			(stroke
				(width 0.1)
				(type default)
			)
			(layer "B.Fab")
		)
		(fp_line
			(start 0.8636 -0.4064)
			(end 0.8636 -0.4572)
			(stroke
				(width 0.1)
				(type default)
			)
			(layer "B.Fab")
		)
		(fp_line
			(start 0.8636 -0.4572)
			(end -0.8636 -0.4572)
			(stroke
				(width 0.1)
				(type default)
			)
			(layer "B.Fab")
		)
		(fp_line
			(start -0.8636 0.4572)
			(end 0.8636 0.4572)
			(stroke
				(width 0.1)
				(type default)
			)
			(layer "B.Fab")
		)
		(fp_line
			(start -0.8636 0.4064)
			(end -0.8636 0.4572)
			(stroke
				(width 0.1)
				(type default)
			)
			(layer "B.Fab")
		)
		(fp_line
			(start -0.8636 -0.4064)
			(end -1.1938 -0.4064)
			(stroke
				(width 0.1)
				(type default)
			)
			(layer "B.Fab")
		)
		(fp_line
			(start -0.8636 -0.4572)
			(end -0.8636 -0.4064)
			(stroke
				(width 0.1)
				(type default)
			)
			(layer "B.Fab")
		)
		(fp_line
			(start -1.1938 0.4064)
			(end -0.8636 0.4064)
			(stroke
				(width 0.1)
				(type default)
			)
			(layer "B.Fab")
		)
		(fp_line
			(start -1.1938 -0.4064)
			(end -1.1938 0.4064)
			(stroke
				(width 0.1)
				(type default)
			)
			(layer "B.Fab")
		)
		(pad "1" smd rect
			(at 0.7366 0 90)
			(size 0.7112 0.8128)
			(layers "B.Cu" "B.Mask" "B.Paste")
			(net "PVNN_TERM_CPU0")
		)
		(pad "2" smd rect
			(at -0.7366 0 90)
			(size 0.7112 0.8128)
			(layers "B.Cu" "B.Mask" "B.Paste")
			(net "GND")
		)
	)
)
